(kicad_pcb
	(version 20260206)
	(generator "pcbnew")
	(generator_version "10.0")
	(general
		(thickness 1.6)
		(legacy_teardrops no)
	)
	(paper "A4")
	(title_block
		(title "12092022_DA0F0TMDCD0_F0T_Management_Board_D_brd_V3_OCP.brd")
		(comment 1 "Grand Teton / footprints 1428-1433 of 1440")
	)
	(layers
		(0 "F.Cu" signal "TOP")
		(4 "In1.Cu" signal "GND")
		(6 "In2.Cu" signal "IN1")
		(8 "In3.Cu" signal "GND1")
		(10 "In4.Cu" signal "IN2")
		(12 "In5.Cu" signal "VCC")
		(14 "In6.Cu" signal "VCC1")
		(16 "In7.Cu" signal "IN3")
		(18 "In8.Cu" signal "GND2")
		(20 "In9.Cu" signal "IN4")
		(22 "In10.Cu" signal "GND3")
		(2 "B.Cu" signal "BOTTOM")
		(9 "F.Adhes" user "F.Adhesive")
		(11 "B.Adhes" user "B.Adhesive")
		(13 "F.Paste" user "Package Geometry/Pastemask Top")
		(15 "B.Paste" user "Package Geometry/Pastemask Bottom")
		(5 "F.SilkS" user "Ref Des/Silkscreen Top")
		(7 "B.SilkS" user "Ref Des/Silkscreen Bottom")
		(1 "F.Mask" user "Board Geometry/Soldermask Top")
		(3 "B.Mask" user "Board Geometry/Soldermask Bottom")
		(17 "Dwgs.User" user "User.Drawings")
		(19 "Cmts.User" user "User.Comments")
		(21 "Eco1.User" user "User.Eco1")
		(23 "Eco2.User" user "User.Eco2")
		(25 "Edge.Cuts" user "Board Geometry/Outline")
		(27 "Margin" user)
		(31 "F.CrtYd" user "Package Geometry/Place Bound Top")
		(29 "B.CrtYd" user "Package Geometry/Place Bound Bottom")
		(35 "F.Fab" user "Ref Des/Assembly Top")
		(33 "B.Fab" user "Ref Des/Assembly Bottom")
	)
	(footprint ""
		(layer "B.Cu")
		(at 36.77412 -97.22104 180)
		(property "Reference" "R731"
			(at 0 0 0)
			(layer "B.SilkS")
			(hide yes)
			(effects
				(font
					(size 1.27 1.27)
				)
				(justify mirror)
			)
		)
		(property "Value" ""
			(at 0 0 0)
			(layer "B.Fab")
			(effects
				(font
					(size 1.27 1.27)
				)
				(justify mirror)
			)
		)
		(duplicate_pad_numbers_are_jumpers no)
		(fp_line
			(start 0.7874 0.4064)
			(end 0.7874 -0.4064)
			(stroke
				(width 0.1524)
				(type default)
			)
			(layer "B.SilkS")
		)
		(fp_line
			(start 0.7874 -0.4064)
			(end -0.7874 -0.4064)
			(stroke
				(width 0.1524)
				(type default)
			)
			(layer "B.SilkS")
		)
		(fp_line
			(start -0.7874 0.4064)
			(end 0.7874 0.4064)
			(stroke
				(width 0.1524)
				(type default)
			)
			(layer "B.SilkS")
		)
		(fp_line
			(start -0.7874 -0.4064)
			(end -0.7874 0.4064)
			(stroke
				(width 0.1524)
				(type default)
			)
			(layer "B.SilkS")
		)
		(fp_line
			(start 0.67945 0.3048)
			(end 0.67945 -0.305054)
			(stroke
				(width 0.1)
				(type default)
			)
			(layer "B.Fab")
		)
		(fp_line
			(start 0.67945 -0.305054)
			(end 0.12065 -0.305054)
			(stroke
				(width 0.1)
				(type default)
			)
			(layer "B.Fab")
		)
		(fp_line
			(start 0.12065 0.3048)
			(end 0.67945 0.3048)
			(stroke
				(width 0.1)
				(type default)
			)
			(layer "B.Fab")
		)
		(fp_line
			(start 0.12065 0.2794)
			(end 0.12065 0.3048)
			(stroke
				(width 0.1)
				(type default)
			)
			(layer "B.Fab")
		)
		(fp_line
			(start 0.12065 -0.2794)
			(end -0.12065 -0.2794)
			(stroke
				(width 0.1)
				(type default)
			)
			(layer "B.Fab")
		)
		(fp_line
			(start 0.12065 -0.305054)
			(end 0.12065 -0.2794)
			(stroke
				(width 0.1)
				(type default)
			)
			(layer "B.Fab")
		)
		(fp_line
			(start -0.120396 0.3048)
			(end -0.120396 0.2794)
			(stroke
				(width 0.1)
				(type default)
			)
			(layer "B.Fab")
		)
		(fp_line
			(start -0.120396 0.2794)
			(end 0.12065 0.2794)
			(stroke
				(width 0.1)
				(type default)
			)
			(layer "B.Fab")
		)
		(fp_line
			(start -0.12065 -0.2794)
			(end -0.12065 -0.3048)
			(stroke
				(width 0.1)
				(type default)
			)
			(layer "B.Fab")
		)
		(fp_line
			(start -0.12065 -0.3048)
			(end -0.67945 -0.3048)
			(stroke
				(width 0.1)
				(type default)
			)
			(layer "B.Fab")
		)
		(fp_line
			(start -0.67945 0.3048)
			(end -0.120396 0.3048)
			(stroke
				(width 0.1)
				(type default)
			)
			(layer "B.Fab")
		)
		(fp_line
			(start -0.67945 -0.3048)
			(end -0.67945 0.3048)
			(stroke
				(width 0.1)
				(type default)
			)
			(layer "B.Fab")
		)
		(pad "1" smd circle
			(at 0.40005 0)
			(size 0 0)
			(layers "B.Cu" "B.Mask" "B.Paste")
			(net "SMB_DEBUG_AUX_LVC3_USB_SDA")
		)
		(pad "2" smd circle
			(at -0.40005 0)
			(size 0 0)
			(layers "B.Cu" "B.Mask" "B.Paste")
			(net "SMB_DEBUG_AUX_LVC3_USB_R2_SDA")
		)
	)
	(footprint ""
		(layer "B.Cu")
		(at 42.909236 -71.589392)
		(property "Reference" "R777"
			(at 0 0 0)
			(layer "B.SilkS")
			(hide yes)
			(effects
				(font
					(size 1.27 1.27)
				)
				(justify mirror)
			)
		)
		(property "Value" ""
			(at 0 0 0)
			(layer "B.Fab")
			(effects
				(font
					(size 1.27 1.27)
				)
				(justify mirror)
			)
		)
		(duplicate_pad_numbers_are_jumpers no)
		(fp_line
			(start -0.7874 -0.4064)
			(end -0.7874 0.4064)
			(stroke
				(width 0.1524)
				(type default)
			)
			(layer "B.SilkS")
		)
		(fp_line
			(start -0.7874 0.4064)
			(end 0.7874 0.4064)
			(stroke
				(width 0.1524)
				(type default)
			)
			(layer "B.SilkS")
		)
		(fp_line
			(start 0.7874 -0.4064)
			(end -0.7874 -0.4064)
			(stroke
				(width 0.1524)
				(type default)
			)
			(layer "B.SilkS")
		)
		(fp_line
			(start 0.7874 0.4064)
			(end 0.7874 -0.4064)
			(stroke
				(width 0.1524)
				(type default)
			)
			(layer "B.SilkS")
		)
		(fp_line
			(start -0.67945 -0.3048)
			(end -0.67945 0.3048)
			(stroke
				(width 0.1)
				(type default)
			)
			(layer "B.Fab")
		)
		(fp_line
			(start -0.67945 0.3048)
			(end -0.120396 0.3048)
			(stroke
				(width 0.1)
				(type default)
			)
			(layer "B.Fab")
		)
		(fp_line
			(start -0.12065 -0.3048)
			(end -0.67945 -0.3048)
			(stroke
				(width 0.1)
				(type default)
			)
			(layer "B.Fab")
		)
		(fp_line
			(start -0.12065 -0.2794)
			(end -0.12065 -0.3048)
			(stroke
				(width 0.1)
				(type default)
			)
			(layer "B.Fab")
		)
		(fp_line
			(start -0.120396 0.2794)
			(end 0.12065 0.2794)
			(stroke
				(width 0.1)
				(type default)
			)
			(layer "B.Fab")
		)
		(fp_line
			(start -0.120396 0.3048)
			(end -0.120396 0.2794)
			(stroke
				(width 0.1)
				(type default)
			)
			(layer "B.Fab")
		)
		(fp_line
			(start 0.12065 -0.305054)
			(end 0.12065 -0.2794)
			(stroke
				(width 0.1)
				(type default)
			)
			(layer "B.Fab")
		)
		(fp_line
			(start 0.12065 -0.2794)
			(end -0.12065 -0.2794)
			(stroke
				(width 0.1)
				(type default)
			)
			(layer "B.Fab")
		)
		(fp_line
			(start 0.12065 0.2794)
			(end 0.12065 0.3048)
			(stroke
				(width 0.1)
				(type default)
			)
			(layer "B.Fab")
		)
		(fp_line
			(start 0.12065 0.3048)
			(end 0.67945 0.3048)
			(stroke
				(width 0.1)
				(type default)
			)
			(layer "B.Fab")
		)
		(fp_line
			(start 0.67945 -0.305054)
			(end 0.12065 -0.305054)
			(stroke
				(width 0.1)
				(type default)
			)
			(layer "B.Fab")
		)
		(fp_line
			(start 0.67945 0.3048)
			(end 0.67945 -0.305054)
			(stroke
				(width 0.1)
				(type default)
			)
			(layer "B.Fab")
		)
		(pad "1" smd circle
			(at 0.40005 0 180)
			(size 0 0)
			(layers "B.Cu" "B.Mask" "B.Paste")
			(net "P3V_BAT_R")
		)
		(pad "2" smd circle
			(at -0.40005 0 180)
			(size 0 0)
			(layers "B.Cu" "B.Mask" "B.Paste")
			(net "P3V_BAT_R1")
		)
	)
	(footprint ""
		(layer "B.Cu")
		(at 69.776848 -39.284402 180)
		(property "Reference" "L3"
			(at 0 0 0)
			(layer "B.SilkS")
			(hide yes)
			(effects
				(font
					(size 1.27 1.27)
				)
				(justify mirror)
			)
		)
		(property "Value" ""
			(at 0 0 0)
			(layer "B.Fab")
			(effects
				(font
					(size 1.27 1.27)
				)
				(justify mirror)
			)
		)
		(duplicate_pad_numbers_are_jumpers no)
		(fp_line
			(start 1.27 0.5842)
			(end 1.27 -0.5842)
			(stroke
				(width 0.1524)
				(type default)
			)
			(layer "B.SilkS")
		)
		(fp_line
			(start 1.27 -0.5588)
			(end 1.27 -0.5842)
			(stroke
				(width 0.1524)
				(type default)
			)
			(layer "B.SilkS")
		)
		(fp_line
			(start 1.27 -0.5842)
			(end -1.27 -0.5842)
			(stroke
				(width 0.1524)
				(type default)
			)
			(layer "B.SilkS")
		)
		(fp_line
			(start 0.127 0.5842)
			(end 0.127 -0.5842)
			(stroke
				(width 0.1524)
				(type default)
			)
			(layer "B.SilkS")
		)
		(fp_line
			(start -0.127 0.5842)
			(end -0.127 -0.5842)
			(stroke
				(width 0.1524)
				(type default)
			)
			(layer "B.SilkS")
		)
		(fp_line
			(start -1.27 0.5842)
			(end 1.27 0.5842)
			(stroke
				(width 0.1524)
				(type default)
			)
			(layer "B.SilkS")
		)
		(fp_line
			(start -1.27 0.5842)
			(end -1.27 -0.5842)
			(stroke
				(width 0.1524)
				(type default)
			)
			(layer "B.SilkS")
		)
		(fp_line
			(start 1.194308 0.406654)
			(end 1.194308 -0.406654)
			(stroke
				(width 0.1)
				(type default)
			)
			(layer "B.Fab")
		)
		(fp_line
			(start 1.194308 -0.406654)
			(end 0.9144 -0.406654)
			(stroke
				(width 0.1)
				(type default)
			)
			(layer "B.Fab")
		)
		(fp_line
			(start 0.9144 0.508)
			(end 0.9144 0.406654)
			(stroke
				(width 0.1)
				(type default)
			)
			(layer "B.Fab")
		)
		(fp_line
			(start 0.9144 0.406654)
			(end 1.194308 0.406654)
			(stroke
				(width 0.1)
				(type default)
			)
			(layer "B.Fab")
		)
		(fp_line
			(start 0.9144 -0.406654)
			(end 0.9144 -0.508)
			(stroke
				(width 0.1)
				(type default)
			)
			(layer "B.Fab")
		)
		(fp_line
			(start 0.9144 -0.508)
			(end -0.9144 -0.508)
			(stroke
				(width 0.1)
				(type default)
			)
			(layer "B.Fab")
		)
		(fp_line
			(start -0.9144 0.508)
			(end 0.9144 0.508)
			(stroke
				(width 0.1)
				(type default)
			)
			(layer "B.Fab")
		)
		(fp_line
			(start -0.9144 0.4064)
			(end -0.9144 0.508)
			(stroke
				(width 0.1)
				(type default)
			)
			(layer "B.Fab")
		)
		(fp_line
			(start -0.9144 -0.406654)
			(end -1.1938 -0.406654)
			(stroke
				(width 0.1)
				(type default)
			)
			(layer "B.Fab")
		)
		(fp_line
			(start -0.9144 -0.508)
			(end -0.9144 -0.406654)
			(stroke
				(width 0.1)
				(type default)
			)
			(layer "B.Fab")
		)
		(fp_line
			(start -1.1938 0.4064)
			(end -0.9144 0.4064)
			(stroke
				(width 0.1)
				(type default)
			)
			(layer "B.Fab")
		)
		(fp_line
			(start -1.1938 -0.406654)
			(end -1.1938 0.4064)
			(stroke
				(width 0.1)
				(type default)
			)
			(layer "B.Fab")
		)
		(pad "1" smd rect
			(at 0.7366 0 90)
			(size 0.7112 0.8128)
			(layers "B.Cu" "B.Mask" "B.Paste")
			(net "P1V8_AUX")
		)
		(pad "2" smd rect
			(at -0.7366 0 90)
			(size 0.7112 0.8128)
			(layers "B.Cu" "B.Mask" "B.Paste")
			(net "P1V8_BMC_USB2AV18")
		)
	)
	(footprint ""
		(layer "B.Cu")
		(at 46.111414 -53.754274 -90)
		(property "Reference" "C83"
			(at 0 0 90)
			(layer "B.SilkS")
			(hide yes)
			(effects
				(font
					(size 1.27 1.27)
				)
				(justify mirror)
			)
		)
		(property "Value" ""
			(at 0 0 90)
			(layer "B.Fab")
			(effects
				(font
					(size 1.27 1.27)
				)
				(justify mirror)
			)
		)
		(duplicate_pad_numbers_are_jumpers no)
		(fp_line
			(start -0.7874 0.4064)
			(end 0.7874 0.4064)
			(stroke
				(width 0.1524)
				(type default)
			)
			(layer "B.SilkS")
		)
		(fp_line
			(start 0.7874 0.4064)
			(end 0.7874 -0.4064)
			(stroke
				(width 0.1524)
				(type default)
			)
			(layer "B.SilkS")
		)
		(fp_line
			(start -0.7874 -0.4064)
			(end -0.7874 0.4064)
			(stroke
				(width 0.1524)
				(type default)
			)
			(layer "B.SilkS")
		)
		(fp_line
			(start 0.7874 -0.4064)
			(end -0.7874 -0.4064)
			(stroke
				(width 0.1524)
				(type default)
			)
			(layer "B.SilkS")
		)
		(fp_line
			(start -0.67945 0.3048)
			(end -0.120396 0.3048)
			(stroke
				(width 0.1)
				(type default)
			)
			(layer "B.Fab")
		)
		(fp_line
			(start -0.120396 0.3048)
			(end -0.120396 0.2794)
			(stroke
				(width 0.1)
				(type default)
			)
			(layer "B.Fab")
		)
		(fp_line
			(start 0.12065 0.3048)
			(end 0.67945 0.3048)
			(stroke
				(width 0.1)
				(type default)
			)
			(layer "B.Fab")
		)
		(fp_line
			(start 0.67945 0.3048)
			(end 0.67945 -0.305054)
			(stroke
				(width 0.1)
				(type default)
			)
			(layer "B.Fab")
		)
		(fp_line
			(start -0.120396 0.2794)
			(end 0.12065 0.2794)
			(stroke
				(width 0.1)
				(type default)
			)
			(layer "B.Fab")
		)
		(fp_line
			(start 0.12065 0.2794)
			(end 0.12065 0.3048)
			(stroke
				(width 0.1)
				(type default)
			)
			(layer "B.Fab")
		)
		(fp_line
			(start -0.12065 -0.2794)
			(end -0.12065 -0.3048)
			(stroke
				(width 0.1)
				(type default)
			)
			(layer "B.Fab")
		)
		(fp_line
			(start 0.12065 -0.2794)
			(end -0.12065 -0.2794)
			(stroke
				(width 0.1)
				(type default)
			)
			(layer "B.Fab")
		)
		(fp_line
			(start -0.67945 -0.3048)
			(end -0.67945 0.3048)
			(stroke
				(width 0.1)
				(type default)
			)
			(layer "B.Fab")
		)
		(fp_line
			(start -0.12065 -0.3048)
			(end -0.67945 -0.3048)
			(stroke
				(width 0.1)
				(type default)
			)
			(layer "B.Fab")
		)
		(fp_line
			(start 0.12065 -0.305054)
			(end 0.12065 -0.2794)
			(stroke
				(width 0.1)
				(type default)
			)
			(layer "B.Fab")
		)
		(fp_line
			(start 0.67945 -0.305054)
			(end 0.12065 -0.305054)
			(stroke
				(width 0.1)
				(type default)
			)
			(layer "B.Fab")
		)
		(pad "1" smd circle
			(at 0.40005 0 90)
			(size 0 0)
			(layers "B.Cu" "B.Mask" "B.Paste")
			(net "P3V3_RTC_AUX")
		)
		(pad "2" smd circle
			(at -0.40005 0 90)
			(size 0 0)
			(layers "B.Cu" "B.Mask" "B.Paste")
			(net "GND")
		)
	)
	(footprint ""
		(layer "B.Cu")
		(at 71.1708 -34.8996 180)
		(property "Reference" "C44"
			(at 0 0 0)
			(layer "B.SilkS")
			(hide yes)
			(effects
				(font
					(size 1.27 1.27)
				)
				(justify mirror)
			)
		)
		(property "Value" ""
			(at 0 0 0)
			(layer "B.Fab")
			(effects
				(font
					(size 1.27 1.27)
				)
				(justify mirror)
			)
		)
		(duplicate_pad_numbers_are_jumpers no)
		(fp_line
			(start 1.2954 0.5842)
			(end 1.2954 -0.5842)
			(stroke
				(width 0.1524)
				(type default)
			)
			(layer "B.SilkS")
		)
		(fp_line
			(start 1.2954 -0.5842)
			(end -1.2954 -0.5842)
			(stroke
				(width 0.1524)
				(type default)
			)
			(layer "B.SilkS")
		)
		(fp_line
			(start 0 -0.5842)
			(end 0 0.5842)
			(stroke
				(width 0.1524)
				(type default)
			)
			(layer "B.SilkS")
		)
		(fp_line
			(start -1.2954 0.5842)
			(end 1.2954 0.5842)
			(stroke
				(width 0.1524)
				(type default)
			)
			(layer "B.SilkS")
		)
		(fp_line
			(start -1.2954 -0.5842)
			(end -1.2954 0.5842)
			(stroke
				(width 0.1524)
				(type default)
			)
			(layer "B.SilkS")
		)
		(fp_line
			(start 1.1938 0.4064)
			(end 1.1938 -0.4064)
			(stroke
				(width 0.1)
				(type default)
			)
			(layer "B.Fab")
		)
		(fp_line
			(start 1.1938 -0.4064)
			(end 0.8636 -0.4064)
			(stroke
				(width 0.1)
				(type default)
			)
			(layer "B.Fab")
		)
		(fp_line
			(start 0.8636 0.4572)
			(end 0.8636 0.4064)
			(stroke
				(width 0.1)
				(type default)
			)
			(layer "B.Fab")
		)
		(fp_line
			(start 0.8636 0.4064)
			(end 1.1938 0.4064)
			(stroke
				(width 0.1)
				(type default)
			)
			(layer "B.Fab")
		)
		(fp_line
			(start 0.8636 -0.4064)
			(end 0.8636 -0.4572)
			(stroke
				(width 0.1)
				(type default)
			)
			(layer "B.Fab")
		)
		(fp_line
			(start 0.8636 -0.4572)
			(end -0.8636 -0.4572)
			(stroke
				(width 0.1)
				(type default)
			)
			(layer "B.Fab")
		)
		(fp_line
			(start -0.8636 0.4572)
			(end 0.8636 0.4572)
			(stroke
				(width 0.1)
				(type default)
			)
			(layer "B.Fab")
		)
		(fp_line
			(start -0.8636 0.4064)
			(end -0.8636 0.4572)
			(stroke
				(width 0.1)
				(type default)
			)
			(layer "B.Fab")
		)
		(fp_line
			(start -0.8636 -0.4064)
			(end -1.1938 -0.4064)
			(stroke
				(width 0.1)
				(type default)
			)
			(layer "B.Fab")
		)
		(fp_line
			(start -0.8636 -0.4572)
			(end -0.8636 -0.4064)
			(stroke
				(width 0.1)
				(type default)
			)
			(layer "B.Fab")
		)
		(fp_line
			(start -1.1938 0.4064)
			(end -0.8636 0.4064)
			(stroke
				(width 0.1)
				(type default)
			)
			(layer "B.Fab")
		)
		(fp_line
			(start -1.1938 -0.4064)
			(end -1.1938 0.4064)
			(stroke
				(width 0.1)
				(type default)
			)
			(layer "B.Fab")
		)
		(pad "1" smd rect
			(at 0.7366 0 90)
			(size 0.7112 0.8128)
			(layers "B.Cu" "B.Mask" "B.Paste")
			(net "P3V3_BMC_USB2AV33")
		)
		(pad "2" smd rect
			(at -0.7366 0 90)
			(size 0.7112 0.8128)
			(layers "B.Cu" "B.Mask" "B.Paste")
			(net "GND")
		)
	)
	(footprint ""
		(layer "B.Cu")
		(at 81.38922 -46.586394)
		(property "Reference" "R375"
			(at 0 0 0)
			(layer "B.SilkS")
			(hide yes)
			(effects
				(font
					(size 1.27 1.27)
				)
				(justify mirror)
			)
		)
		(property "Value" ""
			(at 0 0 0)
			(layer "B.Fab")
			(effects
				(font
					(size 1.27 1.27)
				)
				(justify mirror)
			)
		)
		(duplicate_pad_numbers_are_jumpers no)
		(fp_line
			(start -0.7874 -0.4064)
			(end -0.7874 0.4064)
			(stroke
				(width 0.1524)
				(type default)
			)
			(layer "B.SilkS")
		)
		(fp_line
			(start -0.7874 0.4064)
			(end 0.7874 0.4064)
			(stroke
				(width 0.1524)
				(type default)
			)
			(layer "B.SilkS")
		)
		(fp_line
			(start 0.7874 -0.4064)
			(end -0.7874 -0.4064)
			(stroke
				(width 0.1524)
				(type default)
			)
			(layer "B.SilkS")
		)
		(fp_line
			(start 0.7874 0.4064)
			(end 0.7874 -0.4064)
			(stroke
				(width 0.1524)
				(type default)
			)
			(layer "B.SilkS")
		)
		(fp_line
			(start -0.67945 -0.3048)
			(end -0.67945 0.3048)
			(stroke
				(width 0.1)
				(type default)
			)
			(layer "B.Fab")
		)
		(fp_line
			(start -0.67945 0.3048)
			(end -0.120396 0.3048)
			(stroke
				(width 0.1)
				(type default)
			)
			(layer "B.Fab")
		)
		(fp_line
			(start -0.12065 -0.3048)
			(end -0.67945 -0.3048)
			(stroke
				(width 0.1)
				(type default)
			)
			(layer "B.Fab")
		)
		(fp_line
			(start -0.12065 -0.2794)
			(end -0.12065 -0.3048)
			(stroke
				(width 0.1)
				(type default)
			)
			(layer "B.Fab")
		)
		(fp_line
			(start -0.120396 0.2794)
			(end 0.12065 0.2794)
			(stroke
				(width 0.1)
				(type default)
			)
			(layer "B.Fab")
		)
		(fp_line
			(start -0.120396 0.3048)
			(end -0.120396 0.2794)
			(stroke
				(width 0.1)
				(type default)
			)
			(layer "B.Fab")
		)
		(fp_line
			(start 0.12065 -0.305054)
			(end 0.12065 -0.2794)
			(stroke
				(width 0.1)
				(type default)
			)
			(layer "B.Fab")
		)
		(fp_line
			(start 0.12065 -0.2794)
			(end -0.12065 -0.2794)
			(stroke
				(width 0.1)
				(type default)
			)
			(layer "B.Fab")
		)
		(fp_line
			(start 0.12065 0.2794)
			(end 0.12065 0.3048)
			(stroke
				(width 0.1)
				(type default)
			)
			(layer "B.Fab")
		)
		(fp_line
			(start 0.12065 0.3048)
			(end 0.67945 0.3048)
			(stroke
				(width 0.1)
				(type default)
			)
			(layer "B.Fab")
		)
		(fp_line
			(start 0.67945 -0.305054)
			(end 0.12065 -0.305054)
			(stroke
				(width 0.1)
				(type default)
			)
			(layer "B.Fab")
		)
		(fp_line
			(start 0.67945 0.3048)
			(end 0.67945 -0.305054)
			(stroke
				(width 0.1)
				(type default)
			)
			(layer "B.Fab")
		)
		(pad "1" smd circle
			(at 0.40005 0 180)
			(size 0 0)
			(layers "B.Cu" "B.Mask" "B.Paste")
			(net "M_BMC_DDR4_MBG1")
		)
		(pad "2" smd circle
			(at -0.40005 0 180)
			(size 0 0)
			(layers "B.Cu" "B.Mask" "B.Paste")
			(net "P1V2_AUX")
		)
	)
)
